(kicad_pcb
	(version 20260206)
	(generator "pcbnew")
	(generator_version "10.0")
	(general
		(thickness 1.6)
		(legacy_teardrops no)
	)
	(paper "A4")
	(title_block
		(title "01162023_DA0F0TEBIF0_F0T_Expander_BD_F_brd_V02_OCP.brd")
		(comment 1 "Grand Teton / footprints 444-451 of 9728")
	)
	(layers
		(0 "F.Cu" signal "TOP")
		(4 "In1.Cu" signal "GND")
		(6 "In2.Cu" signal "VCC")
		(8 "In3.Cu" signal "VCC1")
		(10 "In4.Cu" signal "GND1")
		(12 "In5.Cu" signal "IN1")
		(14 "In6.Cu" signal "GND2")
		(16 "In7.Cu" signal "IN2")
		(18 "In8.Cu" signal "GND3")
		(20 "In9.Cu" signal "IN3")
		(22 "In10.Cu" signal "GND4")
		(24 "In11.Cu" signal "IN4")
		(26 "In12.Cu" signal "GND5")
		(28 "In13.Cu" signal "IN5")
		(30 "In14.Cu" signal "GND6")
		(32 "In15.Cu" signal "IN6")
		(34 "In16.Cu" signal "GND7")
		(2 "B.Cu" signal "BOTTOM")
		(9 "F.Adhes" user "F.Adhesive")
		(11 "B.Adhes" user "B.Adhesive")
		(13 "F.Paste" user "Package Geometry/Pastemask Top")
		(15 "B.Paste" user "Package Geometry/Pastemask Bottom")
		(5 "F.SilkS" user "Ref Des/Silkscreen Top")
		(7 "B.SilkS" user "Ref Des/Silkscreen Bottom")
		(1 "F.Mask" user "Board Geometry/Soldermask Top")
		(3 "B.Mask" user "Board Geometry/Soldermask Bottom")
		(17 "Dwgs.User" user "User.Drawings")
		(19 "Cmts.User" user "User.Comments")
		(21 "Eco1.User" user "User.Eco1")
		(23 "Eco2.User" user "User.Eco2")
		(25 "Edge.Cuts" user "Board Geometry/Outline")
		(27 "Margin" user)
		(31 "F.CrtYd" user "Package Geometry/Place Bound Top")
		(29 "B.CrtYd" user "Package Geometry/Place Bound Bottom")
		(35 "F.Fab" user "Ref Des/Assembly Top")
		(33 "B.Fab" user "Ref Des/Assembly Bottom")
	)
	(footprint ""
		(layer "F.Cu")
		(at 253.376938 -124.008134 90)
		(property "Reference" "PD53"
			(at -3.358134 2.300732 90)
			(unlocked yes)
			(layer "F.SilkS")
			(effects
				(font
					(size 0.7874 0.5842)
					(thickness 0.1524)
				)
				(justify left)
			)
		)
		(property "Value" ""
			(at 0 0 90)
			(layer "F.Fab")
			(effects
				(font
					(size 1.27 1.27)
				)
			)
		)
		(duplicate_pad_numbers_are_jumpers no)
		(fp_line
			(start 4.107942 -1.459992)
			(end 4.107942 1.459992)
			(stroke
				(width 0.1524)
				(type default)
			)
			(layer "F.SilkS")
		)
		(fp_line
			(start -3.400044 -1.459992)
			(end 4.107942 -1.459992)
			(stroke
				(width 0.1524)
				(type default)
			)
			(layer "F.SilkS")
		)
		(fp_line
			(start 4.107942 1.459992)
			(end -3.400044 1.459992)
			(stroke
				(width 0.1524)
				(type default)
			)
			(layer "F.SilkS")
		)
		(fp_line
			(start -3.400044 1.459992)
			(end -3.400044 -1.459992)
			(stroke
				(width 0.1524)
				(type default)
			)
			(layer "F.SilkS")
		)
		(fp_poly
			(pts
				(xy 4.107942 -1.459992) (xy 4.107942 1.459992) (xy 3.308096 1.459992) (xy 3.308096 -1.459992)
			)
			(stroke
				(width 0)
				(type default)
			)
			(fill yes)
			(layer "F.SilkS")
		)
		(fp_line
			(start 2.29997 -1.459992)
			(end 2.29997 1.459992)
			(stroke
				(width 0.1)
				(type default)
			)
			(layer "F.Fab")
		)
		(fp_line
			(start -2.29997 -1.459992)
			(end 2.29997 -1.459992)
			(stroke
				(width 0.1)
				(type default)
			)
			(layer "F.Fab")
		)
		(fp_line
			(start 2.29997 1.459992)
			(end -2.29997 1.459992)
			(stroke
				(width 0.1)
				(type default)
			)
			(layer "F.Fab")
		)
		(fp_line
			(start -2.29997 1.459992)
			(end -2.29997 -1.459992)
			(stroke
				(width 0.1)
				(type default)
			)
			(layer "F.Fab")
		)
		(fp_text user "+"
			(at -4.7752 -0.12065 90)
			(unlocked yes)
			(layer "F.SilkS")
			(effects
				(font
					(size 1.905 1.4224)
					(thickness 0.1524)
				)
				(justify left)
			)
		)
		(fp_text user "-"
			(at 5.4102 0.29845 270)
			(unlocked yes)
			(layer "F.SilkS")
			(effects
				(font
					(size 1.905 1.4224)
					(thickness 0.1524)
				)
				(justify left)
			)
		)
		(fp_text user "+"
			(at -4.7752 -0.12065 90)
			(unlocked yes)
			(layer "F.Fab")
			(effects
				(font
					(size 1.905 1.4224)
					(thickness 0.1524)
				)
				(justify left)
			)
		)
		(fp_text user "-"
			(at 5.4102 0.29845 270)
			(unlocked yes)
			(layer "F.Fab")
			(effects
				(font
					(size 1.905 1.4224)
					(thickness 0.1524)
				)
				(justify left)
			)
		)
		(pad "A" smd rect
			(at -1.999996 0 180)
			(size 1.7018 2.5146)
			(layers "F.Cu" "F.Mask" "F.Paste")
			(net "GND")
		)
		(pad "C" smd rect
			(at 1.999996 0 180)
			(size 1.7018 2.5146)
			(layers "F.Cu" "F.Mask" "F.Paste")
			(net "P3V3_NIC4")
		)
	)
	(footprint ""
		(layer "F.Cu")
		(at 324.913244 -356.244906 90)
		(property "Reference" "C563"
			(at 0 0 90)
			(layer "F.SilkS")
			(hide yes)
			(effects
				(font
					(size 1.27 1.27)
				)
			)
		)
		(property "Value" ""
			(at 0 0 90)
			(layer "F.Fab")
			(effects
				(font
					(size 1.27 1.27)
				)
			)
		)
		(duplicate_pad_numbers_are_jumpers no)
		(fp_line
			(start 0.299974 -0.150114)
			(end 0.299974 0.150114)
			(stroke
				(width 0.1)
				(type default)
			)
			(layer "F.Fab")
		)
		(fp_line
			(start -0.299974 -0.150114)
			(end 0.299974 -0.150114)
			(stroke
				(width 0.1)
				(type default)
			)
			(layer "F.Fab")
		)
		(fp_line
			(start 0.299974 0.150114)
			(end -0.299974 0.150114)
			(stroke
				(width 0.1)
				(type default)
			)
			(layer "F.Fab")
		)
		(fp_line
			(start -0.299974 0.150114)
			(end -0.299974 -0.150114)
			(stroke
				(width 0.1)
				(type default)
			)
			(layer "F.Fab")
		)
		(pad "1" smd rect
			(at -0.2667 0 90)
			(size 0.3048 0.381)
			(layers "F.Cu" "F.Mask" "F.Paste")
			(net "P5E_PEX2_STN6_TX_DP<105>")
		)
		(pad "2" smd rect
			(at 0.2667 0 90)
			(size 0.3048 0.381)
			(layers "F.Cu" "F.Mask" "F.Paste")
			(net "P5E_PEX2_STN6_TX_C_DP<105>")
		)
	)
	(footprint ""
		(layer "F.Cu")
		(at 31.007304 -257.439414 -90)
		(property "Reference" "C3020"
			(at 0 0 270)
			(layer "F.SilkS")
			(hide yes)
			(effects
				(font
					(size 1.27 1.27)
				)
			)
		)
		(property "Value" ""
			(at 0 0 270)
			(layer "F.Fab")
			(effects
				(font
					(size 1.27 1.27)
				)
			)
		)
		(duplicate_pad_numbers_are_jumpers no)
		(fp_line
			(start -0.299974 0.150114)
			(end -0.299974 -0.150114)
			(stroke
				(width 0.1)
				(type default)
			)
			(layer "F.Fab")
		)
		(fp_line
			(start 0.299974 0.150114)
			(end -0.299974 0.150114)
			(stroke
				(width 0.1)
				(type default)
			)
			(layer "F.Fab")
		)
		(fp_line
			(start -0.299974 -0.150114)
			(end 0.299974 -0.150114)
			(stroke
				(width 0.1)
				(type default)
			)
			(layer "F.Fab")
		)
		(fp_line
			(start 0.299974 -0.150114)
			(end 0.299974 0.150114)
			(stroke
				(width 0.1)
				(type default)
			)
			(layer "F.Fab")
		)
		(pad "1" smd rect
			(at -0.2667 0 270)
			(size 0.3048 0.381)
			(layers "F.Cu" "F.Mask" "F.Paste")
			(net "P1V8_PLL0_PEX0")
		)
		(pad "2" smd rect
			(at 0.2667 0 270)
			(size 0.3048 0.381)
			(layers "F.Cu" "F.Mask" "F.Paste")
			(net "GND")
		)
	)
	(footprint ""
		(layer "F.Cu")
		(at 384.938524 -119.198898)
		(property "Reference" "C680"
			(at 0 0 0)
			(layer "F.SilkS")
			(hide yes)
			(effects
				(font
					(size 1.27 1.27)
				)
			)
		)
		(property "Value" ""
			(at 0 0 0)
			(layer "F.Fab")
			(effects
				(font
					(size 1.27 1.27)
				)
			)
		)
		(duplicate_pad_numbers_are_jumpers no)
		(fp_line
			(start -0.299974 -0.150114)
			(end 0.299974 -0.150114)
			(stroke
				(width 0.1)
				(type default)
			)
			(layer "F.Fab")
		)
		(fp_line
			(start -0.299974 0.150114)
			(end -0.299974 -0.150114)
			(stroke
				(width 0.1)
				(type default)
			)
			(layer "F.Fab")
		)
		(fp_line
			(start 0.299974 -0.150114)
			(end 0.299974 0.150114)
			(stroke
				(width 0.1)
				(type default)
			)
			(layer "F.Fab")
		)
		(fp_line
			(start 0.299974 0.150114)
			(end -0.299974 0.150114)
			(stroke
				(width 0.1)
				(type default)
			)
			(layer "F.Fab")
		)
		(pad "1" smd rect
			(at -0.2667 0)
			(size 0.3048 0.381)
			(layers "F.Cu" "F.Mask" "F.Paste")
			(net "P5E_PEX3_STN1_TX_DP<24>")
		)
		(pad "2" smd rect
			(at 0.2667 0)
			(size 0.3048 0.381)
			(layers "F.Cu" "F.Mask" "F.Paste")
			(net "P5E_PEX3_STN1_TX_C_DP<24>")
		)
	)
	(footprint ""
		(layer "F.Cu")
		(at 376.312684 -86.5378)
		(property "Reference" "R1745"
			(at 0 0 0)
			(layer "F.SilkS")
			(hide yes)
			(effects
				(font
					(size 1.27 1.27)
				)
			)
		)
		(property "Value" ""
			(at 0 0 0)
			(layer "F.Fab")
			(effects
				(font
					(size 1.27 1.27)
				)
			)
		)
		(duplicate_pad_numbers_are_jumpers no)
		(fp_line
			(start -0.7874 -0.4064)
			(end 0.7874 -0.4064)
			(stroke
				(width 0.1524)
				(type default)
			)
			(layer "F.SilkS")
		)
		(fp_line
			(start -0.7874 0.4064)
			(end -0.7874 -0.4064)
			(stroke
				(width 0.1524)
				(type default)
			)
			(layer "F.SilkS")
		)
		(fp_line
			(start 0.7874 -0.4064)
			(end 0.7874 0.4064)
			(stroke
				(width 0.1524)
				(type default)
			)
			(layer "F.SilkS")
		)
		(fp_line
			(start 0.7874 0.4064)
			(end -0.7874 0.4064)
			(stroke
				(width 0.1524)
				(type default)
			)
			(layer "F.SilkS")
		)
		(fp_line
			(start -0.67945 -0.305054)
			(end -0.12065 -0.305054)
			(stroke
				(width 0.1)
				(type default)
			)
			(layer "F.Fab")
		)
		(fp_line
			(start -0.67945 0.3048)
			(end -0.67945 -0.305054)
			(stroke
				(width 0.1)
				(type default)
			)
			(layer "F.Fab")
		)
		(fp_line
			(start -0.12065 -0.305054)
			(end -0.12065 -0.2794)
			(stroke
				(width 0.1)
				(type default)
			)
			(layer "F.Fab")
		)
		(fp_line
			(start -0.12065 -0.2794)
			(end 0.12065 -0.2794)
			(stroke
				(width 0.1)
				(type default)
			)
			(layer "F.Fab")
		)
		(fp_line
			(start -0.12065 0.2794)
			(end -0.12065 0.3048)
			(stroke
				(width 0.1)
				(type default)
			)
			(layer "F.Fab")
		)
		(fp_line
			(start -0.12065 0.3048)
			(end -0.67945 0.3048)
			(stroke
				(width 0.1)
				(type default)
			)
			(layer "F.Fab")
		)
		(fp_line
			(start 0.120396 0.2794)
			(end -0.12065 0.2794)
			(stroke
				(width 0.1)
				(type default)
			)
			(layer "F.Fab")
		)
		(fp_line
			(start 0.120396 0.3048)
			(end 0.120396 0.2794)
			(stroke
				(width 0.1)
				(type default)
			)
			(layer "F.Fab")
		)
		(fp_line
			(start 0.12065 -0.3048)
			(end 0.67945 -0.3048)
			(stroke
				(width 0.1)
				(type default)
			)
			(layer "F.Fab")
		)
		(fp_line
			(start 0.12065 -0.2794)
			(end 0.12065 -0.3048)
			(stroke
				(width 0.1)
				(type default)
			)
			(layer "F.Fab")
		)
		(fp_line
			(start 0.67945 -0.3048)
			(end 0.67945 0.3048)
			(stroke
				(width 0.1)
				(type default)
			)
			(layer "F.Fab")
		)
		(fp_line
			(start 0.67945 0.3048)
			(end 0.120396 0.3048)
			(stroke
				(width 0.1)
				(type default)
			)
			(layer "F.Fab")
		)
		(pad "1" smd circle
			(at -0.40005 0)
			(size 0 0)
			(layers "F.Cu" "F.Mask" "F.Paste")
			(net "P3V3_AUX")
		)
		(pad "2" smd circle
			(at 0.40005 0)
			(size 0 0)
			(layers "F.Cu" "F.Mask" "F.Paste")
			(net "SMB_BIC_I2C6_MUX_PEX_ADC_R_SDA")
		)
	)
	(footprint ""
		(layer "F.Cu")
		(at 219.711524 -71.458074 -90)
		(property "Reference" "PD104"
			(at 4.300474 -2.692146 90)
			(unlocked yes)
			(layer "F.SilkS")
			(effects
				(font
					(size 0.7874 0.5842)
					(thickness 0.1524)
				)
				(justify left)
			)
		)
		(property "Value" ""
			(at 0 0 270)
			(layer "F.Fab")
			(effects
				(font
					(size 1.27 1.27)
				)
			)
		)
		(duplicate_pad_numbers_are_jumpers no)
		(fp_line
			(start -3.656584 1.970024)
			(end 4.240784 1.970024)
			(stroke
				(width 0.1524)
				(type default)
			)
			(layer "F.SilkS")
		)
		(fp_line
			(start 4.240784 1.970024)
			(end 4.240784 -1.970024)
			(stroke
				(width 0.1524)
				(type default)
			)
			(layer "F.SilkS")
		)
		(fp_line
			(start -3.656584 -1.970024)
			(end -3.656584 1.970024)
			(stroke
				(width 0.1524)
				(type default)
			)
			(layer "F.SilkS")
		)
		(fp_line
			(start 4.240784 -1.970024)
			(end -3.656584 -1.970024)
			(stroke
				(width 0.1524)
				(type default)
			)
			(layer "F.SilkS")
		)
		(fp_poly
			(pts
				(xy 3.580384 1.970024) (xy 3.580384 -1.970024) (xy 4.240784 -1.970024) (xy 4.240784 1.970024)
			)
			(stroke
				(width 0)
				(type default)
			)
			(fill yes)
			(layer "F.SilkS")
		)
		(fp_line
			(start -2.3749 1.970024)
			(end 2.3749 1.970024)
			(stroke
				(width 0.1)
				(type default)
			)
			(layer "F.Fab")
		)
		(fp_line
			(start 2.3749 1.970024)
			(end 2.3749 -1.970024)
			(stroke
				(width 0.1)
				(type default)
			)
			(layer "F.Fab")
		)
		(fp_line
			(start -2.3749 -1.970024)
			(end -2.3749 1.970024)
			(stroke
				(width 0.1)
				(type default)
			)
			(layer "F.Fab")
		)
		(fp_line
			(start 2.3749 -1.970024)
			(end -2.3749 -1.970024)
			(stroke
				(width 0.1)
				(type default)
			)
			(layer "F.Fab")
		)
		(fp_text user "+"
			(at -4.9784 -0.23495 270)
			(unlocked yes)
			(layer "F.Fab")
			(effects
				(font
					(size 1.905 1.4224)
					(thickness 0.1524)
				)
				(justify left)
			)
		)
		(fp_text user "-"
			(at 4.1656 -0.23495 270)
			(unlocked yes)
			(layer "F.Fab")
			(effects
				(font
					(size 1.905 1.4224)
					(thickness 0.1524)
				)
				(justify left)
			)
		)
		(pad "A" smd rect
			(at -2.450084 0 270)
			(size 2.159 2.2606)
			(layers "F.Cu" "F.Mask" "F.Paste")
			(net "GND")
		)
		(pad "C" smd rect
			(at 2.450084 0 270)
			(size 2.159 2.2606)
			(layers "F.Cu" "F.Mask" "F.Paste")
			(net "P12V_AUX")
		)
	)
	(footprint ""
		(layer "F.Cu")
		(at 405.247348 -36.686998 90)
		(property "Reference" "C3674"
			(at 0 0 90)
			(layer "F.SilkS")
			(hide yes)
			(effects
				(font
					(size 1.27 1.27)
				)
			)
		)
		(property "Value" ""
			(at 0 0 90)
			(layer "F.Fab")
			(effects
				(font
					(size 1.27 1.27)
				)
			)
		)
		(duplicate_pad_numbers_are_jumpers no)
		(fp_line
			(start 0.7874 -0.4064)
			(end 0.7874 0.4064)
			(stroke
				(width 0.1524)
				(type default)
			)
			(layer "F.SilkS")
		)
		(fp_line
			(start -0.7874 -0.4064)
			(end 0.7874 -0.4064)
			(stroke
				(width 0.1524)
				(type default)
			)
			(layer "F.SilkS")
		)
		(fp_line
			(start 0.7874 0.4064)
			(end -0.7874 0.4064)
			(stroke
				(width 0.1524)
				(type default)
			)
			(layer "F.SilkS")
		)
		(fp_line
			(start -0.7874 0.4064)
			(end -0.7874 -0.4064)
			(stroke
				(width 0.1524)
				(type default)
			)
			(layer "F.SilkS")
		)
		(fp_line
			(start -0.12065 -0.305054)
			(end -0.12065 -0.2794)
			(stroke
				(width 0.1)
				(type default)
			)
			(layer "F.Fab")
		)
		(fp_line
			(start -0.67945 -0.305054)
			(end -0.12065 -0.305054)
			(stroke
				(width 0.1)
				(type default)
			)
			(layer "F.Fab")
		)
		(fp_line
			(start 0.67945 -0.3048)
			(end 0.67945 0.3048)
			(stroke
				(width 0.1)
				(type default)
			)
			(layer "F.Fab")
		)
		(fp_line
			(start 0.12065 -0.3048)
			(end 0.67945 -0.3048)
			(stroke
				(width 0.1)
				(type default)
			)
			(layer "F.Fab")
		)
		(fp_line
			(start 0.12065 -0.2794)
			(end 0.12065 -0.3048)
			(stroke
				(width 0.1)
				(type default)
			)
			(layer "F.Fab")
		)
		(fp_line
			(start -0.12065 -0.2794)
			(end 0.12065 -0.2794)
			(stroke
				(width 0.1)
				(type default)
			)
			(layer "F.Fab")
		)
		(fp_line
			(start 0.120396 0.2794)
			(end -0.12065 0.2794)
			(stroke
				(width 0.1)
				(type default)
			)
			(layer "F.Fab")
		)
		(fp_line
			(start -0.12065 0.2794)
			(end -0.12065 0.3048)
			(stroke
				(width 0.1)
				(type default)
			)
			(layer "F.Fab")
		)
		(fp_line
			(start 0.67945 0.3048)
			(end 0.120396 0.3048)
			(stroke
				(width 0.1)
				(type default)
			)
			(layer "F.Fab")
		)
		(fp_line
			(start 0.120396 0.3048)
			(end 0.120396 0.2794)
			(stroke
				(width 0.1)
				(type default)
			)
			(layer "F.Fab")
		)
		(fp_line
			(start -0.12065 0.3048)
			(end -0.67945 0.3048)
			(stroke
				(width 0.1)
				(type default)
			)
			(layer "F.Fab")
		)
		(fp_line
			(start -0.67945 0.3048)
			(end -0.67945 -0.305054)
			(stroke
				(width 0.1)
				(type default)
			)
			(layer "F.Fab")
		)
		(pad "1" smd circle
			(at -0.40005 0 90)
			(size 0 0)
			(layers "F.Cu" "F.Mask" "F.Paste")
			(net "P3V3_AUX")
		)
		(pad "2" smd circle
			(at 0.40005 0 90)
			(size 0 0)
			(layers "F.Cu" "F.Mask" "F.Paste")
			(net "GND")
		)
	)
	(footprint ""
		(layer "F.Cu")
		(at 26.930096 -290.805108 -90)
		(property "Reference" "C3063"
			(at 0 0 270)
			(layer "F.SilkS")
			(hide yes)
			(effects
				(font
					(size 1.27 1.27)
				)
			)
		)
		(property "Value" ""
			(at 0 0 270)
			(layer "F.Fab")
			(effects
				(font
					(size 1.27 1.27)
				)
			)
		)
		(duplicate_pad_numbers_are_jumpers no)
		(fp_line
			(start -1.2954 0.5842)
			(end -1.2954 -0.5842)
			(stroke
				(width 0.1524)
				(type default)
			)
			(layer "F.SilkS")
		)
		(fp_line
			(start 1.2954 0.5842)
			(end -1.2954 0.5842)
			(stroke
				(width 0.1524)
				(type default)
			)
			(layer "F.SilkS")
		)
		(fp_line
			(start -1.2954 -0.5842)
			(end 1.2954 -0.5842)
			(stroke
				(width 0.1524)
				(type default)
			)
			(layer "F.SilkS")
		)
		(fp_line
			(start 1.2954 -0.5842)
			(end 1.2954 0.5842)
			(stroke
				(width 0.1524)
				(type default)
			)
			(layer "F.SilkS")
		)
		(fp_line
			(start -0.8636 0.4572)
			(end -0.8636 0.4064)
			(stroke
				(width 0.1)
				(type default)
			)
			(layer "F.Fab")
		)
		(fp_line
			(start 0.8636 0.4572)
			(end -0.8636 0.4572)
			(stroke
				(width 0.1)
				(type default)
			)
			(layer "F.Fab")
		)
		(fp_line
			(start -1.1938 0.4064)
			(end -1.1938 -0.4064)
			(stroke
				(width 0.1)
				(type default)
			)
			(layer "F.Fab")
		)
		(fp_line
			(start -0.8636 0.4064)
			(end -1.1938 0.4064)
			(stroke
				(width 0.1)
				(type default)
			)
			(layer "F.Fab")
		)
		(fp_line
			(start 0.8636 0.4064)
			(end 0.8636 0.4572)
			(stroke
				(width 0.1)
				(type default)
			)
			(layer "F.Fab")
		)
		(fp_line
			(start 1.1938 0.4064)
			(end 0.8636 0.4064)
			(stroke
				(width 0.1)
				(type default)
			)
			(layer "F.Fab")
		)
		(fp_line
			(start -1.1938 -0.4064)
			(end -0.8636 -0.4064)
			(stroke
				(width 0.1)
				(type default)
			)
			(layer "F.Fab")
		)
		(fp_line
			(start -0.8636 -0.4064)
			(end -0.8636 -0.4572)
			(stroke
				(width 0.1)
				(type default)
			)
			(layer "F.Fab")
		)
		(fp_line
			(start 0.8636 -0.4064)
			(end 1.1938 -0.4064)
			(stroke
				(width 0.1)
				(type default)
			)
			(layer "F.Fab")
		)
		(fp_line
			(start 1.1938 -0.4064)
			(end 1.1938 0.4064)
			(stroke
				(width 0.1)
				(type default)
			)
			(layer "F.Fab")
		)
		(fp_line
			(start -0.8636 -0.4572)
			(end 0.8636 -0.4572)
			(stroke
				(width 0.1)
				(type default)
			)
			(layer "F.Fab")
		)
		(fp_line
			(start 0.8636 -0.4572)
			(end 0.8636 -0.4064)
			(stroke
				(width 0.1)
				(type default)
			)
			(layer "F.Fab")
		)
		(pad "1" smd rect
			(at -0.7366 0 180)
			(size 0.7112 0.8128)
			(layers "F.Cu" "F.Mask" "F.Paste")
			(net "P1V8_PLL0_PEX0")
		)
		(pad "2" smd rect
			(at 0.7366 0 180)
			(size 0.7112 0.8128)
			(layers "F.Cu" "F.Mask" "F.Paste")
			(net "GND")
		)
	)
)
